(kicad_pcb
	(version 20260206)
	(generator "pcbnew")
	(generator_version "10.0")
	(general
		(thickness 1.6)
		(legacy_teardrops no)
	)
	(paper "A4")
	(title_block
		(title "01162023_DA0F0TEBIF0_F0T_Expander_BD_F_brd_V02_OCP.brd")
		(comment 1 "Grand Teton / footprint 6619 of 9728 (PEX0), pads 1881-1997 of 2397")
	)
	(layers
		(0 "F.Cu" signal "TOP")
		(4 "In1.Cu" signal "GND")
		(6 "In2.Cu" signal "VCC")
		(8 "In3.Cu" signal "VCC1")
		(10 "In4.Cu" signal "GND1")
		(12 "In5.Cu" signal "IN1")
		(14 "In6.Cu" signal "GND2")
		(16 "In7.Cu" signal "IN2")
		(18 "In8.Cu" signal "GND3")
		(20 "In9.Cu" signal "IN3")
		(22 "In10.Cu" signal "GND4")
		(24 "In11.Cu" signal "IN4")
		(26 "In12.Cu" signal "GND5")
		(28 "In13.Cu" signal "IN5")
		(30 "In14.Cu" signal "GND6")
		(32 "In15.Cu" signal "IN6")
		(34 "In16.Cu" signal "GND7")
		(2 "B.Cu" signal "BOTTOM")
		(9 "F.Adhes" user "F.Adhesive")
		(11 "B.Adhes" user "B.Adhesive")
		(13 "F.Paste" user "Package Geometry/Pastemask Top")
		(15 "B.Paste" user "Package Geometry/Pastemask Bottom")
		(5 "F.SilkS" user "Ref Des/Silkscreen Top")
		(7 "B.SilkS" user "Ref Des/Silkscreen Bottom")
		(1 "F.Mask" user "Board Geometry/Soldermask Top")
		(3 "B.Mask" user "Board Geometry/Soldermask Bottom")
		(17 "Dwgs.User" user "User.Drawings")
		(19 "Cmts.User" user "User.Comments")
		(21 "Eco1.User" user "User.Eco1")
		(23 "Eco2.User" user "User.Eco2")
		(25 "Edge.Cuts" user "Board Geometry/Outline")
		(27 "Margin" user)
		(31 "F.CrtYd" user "Package Geometry/Place Bound Top")
		(29 "B.CrtYd" user "Package Geometry/Place Bound Bottom")
		(35 "F.Fab" user "Ref Des/Assembly Top")
		(33 "B.Fab" user "Ref Des/Assembly Bottom")
	)
	(footprint ""
		(layer "F.Cu")
		(at 59.649868 -295.89984)
		(property "Reference" "PEX0"
			(at -3.360166 35.566858 0)
			(unlocked yes)
			(layer "F.SilkS")
			(effects
				(font
					(size 2.032 1.524)
					(thickness 0.1524)
				)
				(justify left)
			)
		)
		(property "Value" ""
			(at 0 0 0)
			(layer "F.Fab")
			(effects
				(font
					(size 1.27 1.27)
				)
			)
		)
		(duplicate_pad_numbers_are_jumpers no)
		(pad "K23" smd circle
			(at -1.89992 -14.249908)
			(size 0.4572 0.4572)
			(layers "F.Cu" "F.Mask" "F.Paste")
			(net "GND")
		)
		(pad "K24" smd circle
			(at -0.94996 -14.249908)
			(size 0.4572 0.4572)
			(layers "F.Cu" "F.Mask" "F.Paste")
			(net "GND")
		)
		(pad "K25" smd circle
			(at 0 -14.249908)
			(size 0.4572 0.4572)
			(layers "F.Cu" "F.Mask" "F.Paste")
			(net "GND")
		)
		(pad "K26" smd circle
			(at 0.94996 -14.249908)
			(size 0.4572 0.4572)
			(layers "F.Cu" "F.Mask" "F.Paste")
			(net "GND")
		)
		(pad "K27" smd circle
			(at 1.89992 -14.249908)
			(size 0.4572 0.4572)
			(layers "F.Cu" "F.Mask" "F.Paste")
			(net "GND")
		)
		(pad "K28" smd circle
			(at 2.84988 -14.249908)
			(size 0.4572 0.4572)
			(layers "F.Cu" "F.Mask" "F.Paste")
			(net "GND")
		)
		(pad "K29" smd circle
			(at 3.800094 -14.249908)
			(size 0.4572 0.4572)
			(layers "F.Cu" "F.Mask" "F.Paste")
			(net "GND")
		)
		(pad "K30" smd circle
			(at 4.750054 -14.249908)
			(size 0.4572 0.4572)
			(layers "F.Cu" "F.Mask" "F.Paste")
			(net "GND")
		)
		(pad "K31" smd circle
			(at 5.700014 -14.249908)
			(size 0.4572 0.4572)
			(layers "F.Cu" "F.Mask" "F.Paste")
			(net "GND")
		)
		(pad "K32" smd circle
			(at 6.649974 -14.249908)
			(size 0.4572 0.4572)
			(layers "F.Cu" "F.Mask" "F.Paste")
			(net "GND")
		)
		(pad "K33" smd circle
			(at 7.599934 -14.249908)
			(size 0.4572 0.4572)
			(layers "F.Cu" "F.Mask" "F.Paste")
			(net "GND")
		)
		(pad "K34" smd circle
			(at 8.549894 -14.249908)
			(size 0.4572 0.4572)
			(layers "F.Cu" "F.Mask" "F.Paste")
			(net "GND")
		)
		(pad "K35" smd circle
			(at 9.500108 -14.249908)
			(size 0.4572 0.4572)
			(layers "F.Cu" "F.Mask" "F.Paste")
			(net "GND")
		)
		(pad "K36" smd circle
			(at 10.450068 -14.249908)
			(size 0.4572 0.4572)
			(layers "F.Cu" "F.Mask" "F.Paste")
			(net "GND")
		)
		(pad "K37" smd circle
			(at 11.400028 -14.249908)
			(size 0.4572 0.4572)
			(layers "F.Cu" "F.Mask" "F.Paste")
			(net "GND")
		)
		(pad "K38" smd circle
			(at 12.349988 -14.249908)
			(size 0.4572 0.4572)
			(layers "F.Cu" "F.Mask" "F.Paste")
			(net "GND")
		)
		(pad "K39" smd circle
			(at 13.299948 -14.249908)
			(size 0.4572 0.4572)
			(layers "F.Cu" "F.Mask" "F.Paste")
			(net "GND")
		)
		(pad "K40" smd circle
			(at 14.249908 -14.249908)
			(size 0.4572 0.4572)
			(layers "F.Cu" "F.Mask" "F.Paste")
			(net "GND")
		)
		(pad "K41" smd circle
			(at 15.200122 -14.249908)
			(size 0.4572 0.4572)
			(layers "F.Cu" "F.Mask" "F.Paste")
			(net "GND")
		)
		(pad "K42" smd circle
			(at 16.150082 -14.249908)
			(size 0.4572 0.4572)
			(layers "F.Cu" "F.Mask" "F.Paste")
			(net "GND")
		)
		(pad "K43" smd circle
			(at 17.100042 -14.249908)
			(size 0.4572 0.4572)
			(layers "F.Cu" "F.Mask" "F.Paste")
			(net "GND")
		)
		(pad "K44" smd circle
			(at 18.050002 -14.249908)
			(size 0.4572 0.4572)
			(layers "F.Cu" "F.Mask" "F.Paste")
			(net "GND")
		)
		(pad "K45" smd circle
			(at 18.999962 -14.249908)
			(size 0.4572 0.4572)
			(layers "F.Cu" "F.Mask" "F.Paste")
			(net "GND")
		)
		(pad "K46" smd circle
			(at 19.949922 -14.249908)
			(size 0.4572 0.4572)
			(layers "F.Cu" "F.Mask" "F.Paste")
			(net "GND")
		)
		(pad "K47" smd circle
			(at 20.899882 -14.249908)
			(size 0.4572 0.4572)
			(layers "F.Cu" "F.Mask" "F.Paste")
			(net "GND")
		)
		(pad "K48" smd circle
			(at 21.850096 -14.249908)
			(size 0.4572 0.4572)
			(layers "F.Cu" "F.Mask" "F.Paste")
			(net "P5E_PEX0_STN4_RX_DP<70>")
		)
		(pad "K49" smd circle
			(at 22.800056 -14.249908)
			(size 0.4572 0.4572)
			(layers "F.Cu" "F.Mask" "F.Paste")
			(net "P5E_PEX0_STN4_RX_DN<70>")
		)
		(pad "L1" smd circle
			(at -22.800056 -13.299948)
			(size 0.4572 0.4572)
			(layers "F.Cu" "F.Mask" "F.Paste")
			(net "GND")
		)
		(pad "L2" smd circle
			(at -21.850096 -13.299948)
			(size 0.4572 0.4572)
			(layers "F.Cu" "F.Mask" "F.Paste")
			(net "GND")
		)
		(pad "L3" smd circle
			(at -20.899882 -13.299948)
			(size 0.4572 0.4572)
			(layers "F.Cu" "F.Mask" "F.Paste")
			(net "P5E_PEX0_STN7_RX_DN<120>")
		)
		(pad "L4" smd circle
			(at -19.949922 -13.299948)
			(size 0.4572 0.4572)
			(layers "F.Cu" "F.Mask" "F.Paste")
			(net "P5E_PEX0_STN7_RX_DP<120>")
		)
		(pad "L5" smd circle
			(at -18.999962 -13.299948)
			(size 0.4572 0.4572)
			(layers "F.Cu" "F.Mask" "F.Paste")
			(net "GND")
		)
		(pad "L6" smd circle
			(at -18.050002 -13.299948)
			(size 0.4572 0.4572)
			(layers "F.Cu" "F.Mask" "F.Paste")
			(net "P5E_PEX0_STN7_TX_DN<120>")
		)
		(pad "L7" smd circle
			(at -17.100042 -13.299948)
			(size 0.4572 0.4572)
			(layers "F.Cu" "F.Mask" "F.Paste")
			(net "P5E_PEX0_STN7_TX_DP<120>")
		)
		(pad "L8" smd circle
			(at -16.150082 -13.299948)
			(size 0.4572 0.4572)
			(layers "F.Cu" "F.Mask" "F.Paste")
			(net "GND")
		)
		(pad "L9" smd circle
			(at -15.200122 -13.299948)
			(size 0.4572 0.4572)
			(layers "F.Cu" "F.Mask" "F.Paste")
			(net "GND")
		)
		(pad "L10" smd circle
			(at -14.249908 -13.299948)
			(size 0.4572 0.4572)
			(layers "F.Cu" "F.Mask" "F.Paste")
			(net "GND")
		)
		(pad "L11" smd circle
			(at -13.299948 -13.299948)
			(size 0.4572 0.4572)
			(layers "F.Cu" "F.Mask" "F.Paste")
			(net "GND")
		)
		(pad "L12" smd circle
			(at -12.349988 -13.299948)
			(size 0.4572 0.4572)
			(layers "F.Cu" "F.Mask" "F.Paste")
			(net "PEX0_DBG_MODE0")
		)
		(pad "L13" smd circle
			(at -11.400028 -13.299948)
			(size 0.4572 0.4572)
			(layers "F.Cu" "F.Mask" "F.Paste")
			(net "PEX0_DBG_MODE1")
		)
		(pad "L14" smd circle
			(at -10.450068 -13.299948)
			(size 0.4572 0.4572)
			(layers "F.Cu" "F.Mask" "F.Paste")
			(net "GND")
		)
		(pad "L15" smd circle
			(at -9.500108 -13.299948)
			(size 0.4572 0.4572)
			(layers "F.Cu" "F.Mask" "F.Paste")
			(net "PU_PEX0_ATPG_MODE_L")
		)
		(pad "L16" smd circle
			(at -8.549894 -13.299948)
			(size 0.4572 0.4572)
			(layers "F.Cu" "F.Mask" "F.Paste")
			(net "PU_PEX0_PAD_TRI_L")
		)
		(pad "L17" smd circle
			(at -7.599934 -13.299948)
			(size 0.4572 0.4572)
			(layers "F.Cu" "F.Mask" "F.Paste")
			(net "TP_PEX0_TDI")
		)
		(pad "L18" smd circle
			(at -6.649974 -13.299948)
			(size 0.4572 0.4572)
			(layers "F.Cu" "F.Mask" "F.Paste")
			(net "PEX0_DBG_SEL0")
		)
		(pad "L19" smd circle
			(at -5.700014 -13.299948)
			(size 0.4572 0.4572)
			(layers "F.Cu" "F.Mask" "F.Paste")
			(net "TP_PEX0_TDO")
		)
		(pad "L20" smd circle
			(at -4.750054 -13.299948)
			(size 0.4572 0.4572)
			(layers "F.Cu" "F.Mask" "F.Paste")
			(net "PU_PEX0_TR_TCK")
		)
		(pad "L21" smd circle
			(at -3.800094 -13.299948)
			(size 0.4572 0.4572)
			(layers "F.Cu" "F.Mask" "F.Paste")
			(net "GND")
		)
		(pad "L22" smd circle
			(at -2.84988 -13.299948)
			(size 0.4572 0.4572)
			(layers "F.Cu" "F.Mask" "F.Paste")
			(net "Net_2897")
		)
		(pad "L23" smd circle
			(at -1.89992 -13.299948)
			(size 0.4572 0.4572)
			(layers "F.Cu" "F.Mask" "F.Paste")
			(net "Net_2901")
		)
		(pad "L24" smd circle
			(at -0.94996 -13.299948)
			(size 0.4572 0.4572)
			(layers "F.Cu" "F.Mask" "F.Paste")
			(net "Net_2896")
		)
		(pad "L25" smd circle
			(at 0 -13.299948)
			(size 0.4572 0.4572)
			(layers "F.Cu" "F.Mask" "F.Paste")
			(net "PEX0_SPARE5")
		)
		(pad "L26" smd circle
			(at 0.94996 -13.299948)
			(size 0.4572 0.4572)
			(layers "F.Cu" "F.Mask" "F.Paste")
			(net "PU_PEX0_SIO_BLINK")
		)
		(pad "L27" smd circle
			(at 1.89992 -13.299948)
			(size 0.4572 0.4572)
			(layers "F.Cu" "F.Mask" "F.Paste")
			(net "PEX0_SPARE2")
		)
		(pad "L28" smd circle
			(at 2.84988 -13.299948)
			(size 0.4572 0.4572)
			(layers "F.Cu" "F.Mask" "F.Paste")
			(net "PEX0_SPARE6")
		)
		(pad "L29" smd circle
			(at 3.800094 -13.299948)
			(size 0.4572 0.4572)
			(layers "F.Cu" "F.Mask" "F.Paste")
			(net "Net_2886")
		)
		(pad "L30" smd circle
			(at 4.750054 -13.299948)
			(size 0.4572 0.4572)
			(layers "F.Cu" "F.Mask" "F.Paste")
			(net "PEX0_SPARE1")
		)
		(pad "L31" smd circle
			(at 5.700014 -13.299948)
			(size 0.4572 0.4572)
			(layers "F.Cu" "F.Mask" "F.Paste")
			(net "Net_2890")
		)
		(pad "L32" smd circle
			(at 6.649974 -13.299948)
			(size 0.4572 0.4572)
			(layers "F.Cu" "F.Mask" "F.Paste")
			(net "PEX0_SPARE3")
		)
		(pad "L33" smd circle
			(at 7.599934 -13.299948)
			(size 0.4572 0.4572)
			(layers "F.Cu" "F.Mask" "F.Paste")
			(net "Net_2882")
		)
		(pad "L34" smd circle
			(at 8.549894 -13.299948)
			(size 0.4572 0.4572)
			(layers "F.Cu" "F.Mask" "F.Paste")
			(net "SMB_PEX0_SLAVE1_SCL")
		)
		(pad "L35" smd circle
			(at 9.500108 -13.299948)
			(size 0.4572 0.4572)
			(layers "F.Cu" "F.Mask" "F.Paste")
			(net "Net_2879")
		)
		(pad "L36" smd circle
			(at 10.450068 -13.299948)
			(size 0.4572 0.4572)
			(layers "F.Cu" "F.Mask" "F.Paste")
			(net "Net_2909")
		)
		(pad "L37" smd circle
			(at 11.400028 -13.299948)
			(size 0.4572 0.4572)
			(layers "F.Cu" "F.Mask" "F.Paste")
			(net "PEX0_EXT_GPIO_LATCH_N")
		)
		(pad "L38" smd circle
			(at 12.349988 -13.299948)
			(size 0.4572 0.4572)
			(layers "F.Cu" "F.Mask" "F.Paste")
			(net "Net_2906")
		)
		(pad "L39" smd circle
			(at 13.299948 -13.299948)
			(size 0.4572 0.4572)
			(layers "F.Cu" "F.Mask" "F.Paste")
			(net "SMB_PEX0_SLAVE_SDA")
		)
		(pad "L40" smd circle
			(at 14.249908 -13.299948)
			(size 0.4572 0.4572)
			(layers "F.Cu" "F.Mask" "F.Paste")
			(net "GND")
		)
		(pad "L41" smd circle
			(at 15.200122 -13.299948)
			(size 0.4572 0.4572)
			(layers "F.Cu" "F.Mask" "F.Paste")
			(net "GND")
		)
		(pad "L42" smd circle
			(at 16.150082 -13.299948)
			(size 0.4572 0.4572)
			(layers "F.Cu" "F.Mask" "F.Paste")
			(net "GND")
		)
		(pad "L43" smd circle
			(at 17.100042 -13.299948)
			(size 0.4572 0.4572)
			(layers "F.Cu" "F.Mask" "F.Paste")
			(net "P5E_PEX0_STN4_TX_DP<69>")
		)
		(pad "L44" smd circle
			(at 18.050002 -13.299948)
			(size 0.4572 0.4572)
			(layers "F.Cu" "F.Mask" "F.Paste")
			(net "P5E_PEX0_STN4_TX_DN<69>")
		)
		(pad "L45" smd circle
			(at 18.999962 -13.299948)
			(size 0.4572 0.4572)
			(layers "F.Cu" "F.Mask" "F.Paste")
			(net "GND")
		)
		(pad "L46" smd circle
			(at 19.949922 -13.299948)
			(size 0.4572 0.4572)
			(layers "F.Cu" "F.Mask" "F.Paste")
			(net "P5E_PEX0_STN4_RX_DP<69>")
		)
		(pad "L47" smd circle
			(at 20.899882 -13.299948)
			(size 0.4572 0.4572)
			(layers "F.Cu" "F.Mask" "F.Paste")
			(net "P5E_PEX0_STN4_RX_DN<69>")
		)
		(pad "L48" smd circle
			(at 21.850096 -13.299948)
			(size 0.4572 0.4572)
			(layers "F.Cu" "F.Mask" "F.Paste")
			(net "GND")
		)
		(pad "L49" smd circle
			(at 22.800056 -13.299948)
			(size 0.4572 0.4572)
			(layers "F.Cu" "F.Mask" "F.Paste")
			(net "GND")
		)
		(pad "M1" smd circle
			(at -22.800056 -12.349988)
			(size 0.4572 0.4572)
			(layers "F.Cu" "F.Mask" "F.Paste")
			(net "P5E_PEX0_STN7_RX_DN<119>")
		)
		(pad "M2" smd circle
			(at -21.850096 -12.349988)
			(size 0.4572 0.4572)
			(layers "F.Cu" "F.Mask" "F.Paste")
			(net "P5E_PEX0_STN7_RX_DP<119>")
		)
		(pad "M3" smd circle
			(at -20.899882 -12.349988)
			(size 0.4572 0.4572)
			(layers "F.Cu" "F.Mask" "F.Paste")
			(net "GND")
		)
		(pad "M4" smd circle
			(at -19.949922 -12.349988)
			(size 0.4572 0.4572)
			(layers "F.Cu" "F.Mask" "F.Paste")
			(net "GND")
		)
		(pad "M5" smd circle
			(at -18.999962 -12.349988)
			(size 0.4572 0.4572)
			(layers "F.Cu" "F.Mask" "F.Paste")
			(net "GND")
		)
		(pad "M6" smd circle
			(at -18.050002 -12.349988)
			(size 0.4572 0.4572)
			(layers "F.Cu" "F.Mask" "F.Paste")
			(net "GND")
		)
		(pad "M7" smd circle
			(at -17.100042 -12.349988)
			(size 0.4572 0.4572)
			(layers "F.Cu" "F.Mask" "F.Paste")
			(net "GND")
		)
		(pad "M8" smd circle
			(at -16.150082 -12.349988)
			(size 0.4572 0.4572)
			(layers "F.Cu" "F.Mask" "F.Paste")
			(net "P5E_PEX0_STN7_TX_DN<119>")
		)
		(pad "M9" smd circle
			(at -15.200122 -12.349988)
			(size 0.4572 0.4572)
			(layers "F.Cu" "F.Mask" "F.Paste")
			(net "P5E_PEX0_STN7_TX_DP<119>")
		)
		(pad "M10" smd circle
			(at -14.249908 -12.349988)
			(size 0.4572 0.4572)
			(layers "F.Cu" "F.Mask" "F.Paste")
			(net "GND")
		)
		(pad "M11" smd circle
			(at -13.299948 -12.349988)
			(size 0.4572 0.4572)
			(layers "F.Cu" "F.Mask" "F.Paste")
			(net "GND")
		)
		(pad "M12" smd circle
			(at -12.349988 -12.349988)
			(size 0.4572 0.4572)
			(layers "F.Cu" "F.Mask" "F.Paste")
			(net "GND")
		)
		(pad "M13" smd circle
			(at -11.400028 -12.349988)
			(size 0.4572 0.4572)
			(layers "F.Cu" "F.Mask" "F.Paste")
			(net "IRQ_PEX0_CLKREQ_INT_N")
		)
		(pad "M14" smd circle
			(at -10.450068 -12.349988)
			(size 0.4572 0.4572)
			(layers "F.Cu" "F.Mask" "F.Paste")
			(net "GND")
		)
		(pad "M15" smd circle
			(at -9.500108 -12.349988)
			(size 0.4572 0.4572)
			(layers "F.Cu" "F.Mask" "F.Paste")
			(net "TP_PEX0_TCK")
		)
		(pad "M16" smd circle
			(at -8.549894 -12.349988)
			(size 0.4572 0.4572)
			(layers "F.Cu" "F.Mask" "F.Paste")
			(net "PEX0_DFT_IDDT")
		)
		(pad "M17" smd circle
			(at -7.599934 -12.349988)
			(size 0.4572 0.4572)
			(layers "F.Cu" "F.Mask" "F.Paste")
			(net "RST_PEX0_SYS_N")
		)
		(pad "M18" smd circle
			(at -6.649974 -12.349988)
			(size 0.4572 0.4572)
			(layers "F.Cu" "F.Mask" "F.Paste")
			(net "TP_PEX0_TRST_L")
		)
		(pad "M19" smd circle
			(at -5.700014 -12.349988)
			(size 0.4572 0.4572)
			(layers "F.Cu" "F.Mask" "F.Paste")
			(net "PEX0_DBG_SEL1")
		)
		(pad "M20" smd circle
			(at -4.750054 -12.349988)
			(size 0.4572 0.4572)
			(layers "F.Cu" "F.Mask" "F.Paste")
			(net "TP_PEX0_TMS")
		)
		(pad "M21" smd circle
			(at -3.800094 -12.349988)
			(size 0.4572 0.4572)
			(layers "F.Cu" "F.Mask" "F.Paste")
			(net "GND")
		)
		(pad "M22" smd circle
			(at -2.84988 -12.349988)
			(size 0.4572 0.4572)
			(layers "F.Cu" "F.Mask" "F.Paste")
			(net "Net_2899")
		)
		(pad "M23" smd circle
			(at -1.89992 -12.349988)
			(size 0.4572 0.4572)
			(layers "F.Cu" "F.Mask" "F.Paste")
			(net "Net_2900")
		)
		(pad "M24" smd circle
			(at -0.94996 -12.349988)
			(size 0.4572 0.4572)
			(layers "F.Cu" "F.Mask" "F.Paste")
			(net "Net_2902")
		)
		(pad "M25" smd circle
			(at 0 -12.349988)
			(size 0.4572 0.4572)
			(layers "F.Cu" "F.Mask" "F.Paste")
			(net "PEX0_SPARE4")
		)
		(pad "M26" smd circle
			(at 0.94996 -12.349988)
			(size 0.4572 0.4572)
			(layers "F.Cu" "F.Mask" "F.Paste")
			(net "PEX0_SPARE0")
		)
		(pad "M27" smd circle
			(at 1.89992 -12.349988)
			(size 0.4572 0.4572)
			(layers "F.Cu" "F.Mask" "F.Paste")
			(net "PEX0_SPARE7")
		)
		(pad "M28" smd circle
			(at 2.84988 -12.349988)
			(size 0.4572 0.4572)
			(layers "F.Cu" "F.Mask" "F.Paste")
			(net "I2C0_PEX0_SHPC_SDA")
		)
		(pad "M29" smd circle
			(at 3.800094 -12.349988)
			(size 0.4572 0.4572)
			(layers "F.Cu" "F.Mask" "F.Paste")
			(net "I2C0_PEX0_SHPC_SCL")
		)
		(pad "M30" smd circle
			(at 4.750054 -12.349988)
			(size 0.4572 0.4572)
			(layers "F.Cu" "F.Mask" "F.Paste")
			(net "Net_2880")
		)
		(pad "M31" smd circle
			(at 5.700014 -12.349988)
			(size 0.4572 0.4572)
			(layers "F.Cu" "F.Mask" "F.Paste")
			(net "Net_2881")
		)
		(pad "M32" smd circle
			(at 6.649974 -12.349988)
			(size 0.4572 0.4572)
			(layers "F.Cu" "F.Mask" "F.Paste")
			(net "Net_2891")
		)
		(pad "M33" smd circle
			(at 7.599934 -12.349988)
			(size 0.4572 0.4572)
			(layers "F.Cu" "F.Mask" "F.Paste")
			(net "Net_2885")
		)
		(pad "M34" smd circle
			(at 8.549894 -12.349988)
			(size 0.4572 0.4572)
			(layers "F.Cu" "F.Mask" "F.Paste")
			(net "Net_2889")
		)
		(pad "M35" smd circle
			(at 9.500108 -12.349988)
			(size 0.4572 0.4572)
			(layers "F.Cu" "F.Mask" "F.Paste")
			(net "I2C0_PEX0_SCL")
		)
		(pad "M36" smd circle
			(at 10.450068 -12.349988)
			(size 0.4572 0.4572)
			(layers "F.Cu" "F.Mask" "F.Paste")
			(net "Net_2908")
		)
		(pad "M37" smd circle
			(at 11.400028 -12.349988)
			(size 0.4572 0.4572)
			(layers "F.Cu" "F.Mask" "F.Paste")
			(net "Net_2907")
		)
		(pad "M38" smd circle
			(at 12.349988 -12.349988)
			(size 0.4572 0.4572)
			(layers "F.Cu" "F.Mask" "F.Paste")
			(net "SMB_PEX0_SLAVE1_SDA")
		)
		(pad "M39" smd circle
			(at 13.299948 -12.349988)
			(size 0.4572 0.4572)
			(layers "F.Cu" "F.Mask" "F.Paste")
			(net "I2C0_PEX0_SDA")
		)
		(pad "M40" smd circle
			(at 14.249908 -12.349988)
			(size 0.4572 0.4572)
			(layers "F.Cu" "F.Mask" "F.Paste")
			(net "GND")
		)
		(pad "M41" smd circle
			(at 15.200122 -12.349988)
			(size 0.4572 0.4572)
			(layers "F.Cu" "F.Mask" "F.Paste")
			(net "P5E_PEX0_STN4_TX_DP<68>")
		)
	)
)
